(kicad_pcb
	(version 20240108)
	(generator "pcbnew")
	(generator_version "8.0")
	(general
		(thickness 1.62)
		(legacy_teardrops no)
	)
	(paper "A4")
	(title_block
		(title "Jetson Orin Baseboard")
		(date "2025-03-12")
		(rev "1.3.4")
		(company "Antmicro Ltd")
		(comment 1 "www.antmicro.com")
		(comment 9 "footprints 433-438 of 677")
	)
	(layers
		(0 "F.Cu" signal)
		(1 "In1.Cu" signal)
		(2 "In2.Cu" signal)
		(3 "In3.Cu" signal)
		(4 "In4.Cu" jumper)
		(5 "In5.Cu" signal)
		(6 "In6.Cu" signal)
		(31 "B.Cu" signal)
		(32 "B.Adhes" user "B.Adhesive")
		(33 "F.Adhes" user "F.Adhesive")
		(34 "B.Paste" user)
		(35 "F.Paste" user)
		(36 "B.SilkS" user "B.Silkscreen")
		(37 "F.SilkS" user "F.Silkscreen")
		(38 "B.Mask" user)
		(39 "F.Mask" user)
		(40 "Dwgs.User" user "User.Drawings")
		(41 "Cmts.User" user "User.Comments")
		(42 "Eco1.User" user "User.Eco1")
		(43 "Eco2.User" user "User.Eco2")
		(44 "Edge.Cuts" user)
		(45 "Margin" user)
		(46 "B.CrtYd" user "B.Courtyard")
		(47 "F.CrtYd" user "F.Courtyard")
		(48 "B.Fab" user)
		(49 "F.Fab" user)
	)
	(footprint "antmicro-footprints:R_0402_1005Metric"
		(layer "B.Cu")
		(at 46.9 89.6375)
		(descr "Resistor SMD 0402")
		(tags "resistor SMD 0402")
		(property "Reference" "R145"
			(at 0.335 -3.4775 180)
			(layer "B.SilkS")
			(effects
				(font
					(size 0.7 0.7)
					(thickness 0.15)
				)
				(justify left bottom mirror)
			)
		)
		(property "Value" "R_1k2_0402"
			(at 0 -1.4 180)
			(layer "B.Fab")
			(effects
				(font
					(size 0.7 0.7)
					(thickness 0.15)
				)
				(justify left bottom mirror)
			)
		)
		(property "Footprint" "antmicro-footprints:R_0402_1005Metric"
			(at 0 0 0)
			(layer "F.Fab")
			(hide yes)
			(effects
				(font
					(size 1.27 1.27)
					(thickness 0.15)
				)
			)
		)
		(property "Datasheet" "https://www.bourns.com/docs/product-datasheets/cr.pdf"
			(at 0 0 0)
			(layer "F.Fab")
			(hide yes)
			(effects
				(font
					(size 1.27 1.27)
					(thickness 0.15)
				)
			)
		)
		(property "Author" "Antmicro"
			(at 0 0 0)
			(layer "B.Fab")
			(hide yes)
			(effects
				(font
					(size 1 1)
					(thickness 0.15)
				)
				(justify mirror)
			)
		)
		(property "License" "Apache-2.0"
			(at 0 0 0)
			(layer "B.Fab")
			(hide yes)
			(effects
				(font
					(size 1 1)
					(thickness 0.15)
				)
				(justify mirror)
			)
		)
		(property "MPN" "CR0402-FX-1201GLF"
			(at 0 0 0)
			(layer "B.Fab")
			(hide yes)
			(effects
				(font
					(size 1 1)
					(thickness 0.15)
				)
				(justify mirror)
			)
		)
		(property "Manufacturer" "Bourns"
			(at 0 0 0)
			(layer "B.Fab")
			(hide yes)
			(effects
				(font
					(size 1 1)
					(thickness 0.15)
				)
				(justify mirror)
			)
		)
		(property "Tolerance" "1%"
			(at 0 0 0)
			(layer "B.Fab")
			(hide yes)
			(effects
				(font
					(size 1 1)
					(thickness 0.15)
				)
				(justify mirror)
			)
		)
		(property "Val" "1k2"
			(at 0 0 0)
			(layer "B.Fab")
			(hide yes)
			(effects
				(font
					(size 1 1)
					(thickness 0.15)
				)
				(justify mirror)
			)
		)
		(sheetname "Ethernet")
		(sheetfile "ethernet.kicad_sch")
		(attr smd)
		(fp_rect
			(start -0.925 0.47)
			(end 0.925 -0.47)
			(stroke
				(width 0.05)
				(type default)
			)
			(fill none)
			(layer "B.CrtYd")
		)
		(fp_rect
			(start -0.5 0.25)
			(end 0.5 -0.25)
			(stroke
				(width 0.15)
				(type solid)
			)
			(fill none)
			(layer "B.Fab")
		)
		(fp_text user "${REFERENCE}"
			(at -0.95 -3.168 180)
			(layer "B.Fab")
			(hide yes)
			(effects
				(font
					(size 0.7 0.7)
					(thickness 0.15)
				)
				(justify left bottom mirror)
			)
		)
		(fp_text user "License: Apache-2.0"
			(at -0.95 -5.169 180)
			(layer "B.Fab")
			(hide yes)
			(effects
				(font
					(size 0.7 0.7)
					(thickness 0.15)
				)
				(justify left bottom mirror)
			)
		)
		(fp_text user "Author: Antmicro"
			(at -0.95 -4.169 180)
			(layer "B.Fab")
			(hide yes)
			(effects
				(font
					(size 0.7 0.7)
					(thickness 0.15)
				)
				(justify left bottom mirror)
			)
		)
		(pad "1" smd roundrect
			(at -0.48 0)
			(size 0.59 0.64)
			(layers "B.Cu" "B.Paste" "B.Mask")
			(roundrect_rratio 0.25)
			(net 499 "/Ethernet/VSS")
			(pintype "passive")
		)
		(pad "2" smd roundrect
			(at 0.48 0)
			(size 0.59 0.64)
			(layers "B.Cu" "B.Paste" "B.Mask")
			(roundrect_rratio 0.25)
			(net 569 "/Ethernet/CLSB")
			(pintype "passive")
		)
	)
	(footprint "antmicro-footprints:R_0402_1005Metric"
		(layer "B.Cu")
		(at 76 105.3 -90)
		(descr "Resistor SMD 0402")
		(tags "resistor SMD 0402")
		(property "Reference" "R88"
			(at -5.03 -1.69 90)
			(layer "B.SilkS")
			(effects
				(font
					(size 0.7 0.7)
					(thickness 0.15)
				)
				(justify left bottom mirror)
			)
		)
		(property "Value" "R_1k_0402"
			(at 0 -1.4 90)
			(layer "B.Fab")
			(effects
				(font
					(size 0.7 0.7)
					(thickness 0.15)
				)
				(justify left bottom mirror)
			)
		)
		(property "Footprint" "antmicro-footprints:R_0402_1005Metric"
			(at 0 0 -90)
			(layer "F.Fab")
			(hide yes)
			(effects
				(font
					(size 1.27 1.27)
					(thickness 0.15)
				)
			)
		)
		(property "Datasheet" "https://www.bourns.com/docs/product-datasheets/cr.pdf"
			(at 0 0 -90)
			(layer "F.Fab")
			(hide yes)
			(effects
				(font
					(size 1.27 1.27)
					(thickness 0.15)
				)
			)
		)
		(property "Author" "Antmicro"
			(at -29.3 181.3 0)
			(layer "B.Fab")
			(hide yes)
			(effects
				(font
					(size 1 1)
					(thickness 0.15)
				)
				(justify mirror)
			)
		)
		(property "License" "Apache-2.0"
			(at -29.3 181.3 0)
			(layer "B.Fab")
			(hide yes)
			(effects
				(font
					(size 1 1)
					(thickness 0.15)
				)
				(justify mirror)
			)
		)
		(property "MPN" "CR0402-FX-1001GLF"
			(at -29.3 181.3 0)
			(layer "B.Fab")
			(hide yes)
			(effects
				(font
					(size 1 1)
					(thickness 0.15)
				)
				(justify mirror)
			)
		)
		(property "Manufacturer" "Bourns"
			(at -29.3 181.3 0)
			(layer "B.Fab")
			(hide yes)
			(effects
				(font
					(size 1 1)
					(thickness 0.15)
				)
				(justify mirror)
			)
		)
		(property "Tolerance" "1%"
			(at -29.3 181.3 0)
			(layer "B.Fab")
			(hide yes)
			(effects
				(font
					(size 1 1)
					(thickness 0.15)
				)
				(justify mirror)
			)
		)
		(property "Val" "1k"
			(at -29.3 181.3 0)
			(layer "B.Fab")
			(hide yes)
			(effects
				(font
					(size 1 1)
					(thickness 0.15)
				)
				(justify mirror)
			)
		)
		(sheetname "USB Debug, DP")
		(sheetfile "usb.kicad_sch")
		(attr smd exclude_from_pos_files exclude_from_bom dnp)
		(fp_rect
			(start -0.925 0.47)
			(end 0.925 -0.47)
			(stroke
				(width 0.05)
				(type default)
			)
			(fill none)
			(layer "B.CrtYd")
		)
		(fp_rect
			(start -0.5 0.25)
			(end 0.5 -0.25)
			(stroke
				(width 0.15)
				(type solid)
			)
			(fill none)
			(layer "B.Fab")
		)
		(fp_text user "License: Apache-2.0"
			(at -0.95 -5.169 90)
			(layer "B.Fab")
			(hide yes)
			(effects
				(font
					(size 0.7 0.7)
					(thickness 0.15)
				)
				(justify left bottom mirror)
			)
		)
		(fp_text user "${REFERENCE}"
			(at -0.95 -3.168 90)
			(layer "B.Fab")
			(hide yes)
			(effects
				(font
					(size 0.7 0.7)
					(thickness 0.15)
				)
				(justify left bottom mirror)
			)
		)
		(fp_text user "Author: Antmicro"
			(at -0.95 -4.169 90)
			(layer "B.Fab")
			(hide yes)
			(effects
				(font
					(size 0.7 0.7)
					(thickness 0.15)
				)
				(justify left bottom mirror)
			)
		)
		(pad "1" smd roundrect
			(at -0.48 0 270)
			(size 0.59 0.64)
			(layers "B.Cu" "B.Paste" "B.Mask")
			(roundrect_rratio 0.25)
			(net 305 "/USB Debug, DP/USBC0_SSEQ0")
			(pintype "passive")
		)
		(pad "2" smd roundrect
			(at 0.48 0 270)
			(size 0.59 0.64)
			(layers "B.Cu" "B.Paste" "B.Mask")
			(roundrect_rratio 0.25)
			(net 1 "GND")
			(pintype "passive")
		)
	)
	(footprint "antmicro-footprints:XDFN-2_1x0.60mm"
		(layer "B.Cu")
		(at 101.5 123.8)
		(property "Reference" "D55"
			(at -1.05 -0.6 180)
			(layer "B.SilkS")
			(effects
				(font
					(size 0.7 0.7)
					(thickness 0.15)
				)
				(justify right bottom mirror)
			)
		)
		(property "Value" "TPD1E0B04_XDFN-2"
			(at 0 -1.5 180)
			(layer "B.Fab")
			(effects
				(font
					(size 0.7 0.7)
					(thickness 0.15)
				)
				(justify left bottom mirror)
			)
		)
		(property "Footprint" "antmicro-footprints:XDFN-2_1x0.60mm"
			(at 0 0 0)
			(layer "F.Fab")
			(hide yes)
			(effects
				(font
					(size 1.27 1.27)
					(thickness 0.15)
				)
			)
		)
		(property "Datasheet" "https://www.ti.com/general/docs/suppproductinfo.tsp?distId=26&gotoUrl=https://www.ti.com/lit/gpn/tpd1e0b04"
			(at 0 0 0)
			(layer "F.Fab")
			(hide yes)
			(effects
				(font
					(size 1.27 1.27)
					(thickness 0.15)
				)
			)
		)
		(property "MPN" "TPD1E0B04DPYR"
			(at 0 0 0)
			(layer "B.Fab")
			(hide yes)
			(effects
				(font
					(size 1 1)
					(thickness 0.15)
				)
				(justify mirror)
			)
		)
		(property "Manufacturer" "Texas Instruments"
			(at 0 0 0)
			(layer "B.Fab")
			(hide yes)
			(effects
				(font
					(size 1 1)
					(thickness 0.15)
				)
				(justify mirror)
			)
		)
		(property "Author" "Antmicro"
			(at 0 0 0)
			(layer "B.Fab")
			(hide yes)
			(effects
				(font
					(size 1 1)
					(thickness 0.15)
				)
				(justify mirror)
			)
		)
		(property "License" "Apache-2.0"
			(at 0 0 0)
			(layer "B.Fab")
			(hide yes)
			(effects
				(font
					(size 1 1)
					(thickness 0.15)
				)
				(justify mirror)
			)
		)
		(sheetname "SoM")
		(sheetfile "som.kicad_sch")
		(attr smd)
		(fp_rect
			(start -0.725 0.475)
			(end 0.725 -0.475)
			(stroke
				(width 0.05)
				(type solid)
			)
			(fill none)
			(layer "B.CrtYd")
		)
		(fp_rect
			(start -0.55 0.35)
			(end 0.55 -0.35)
			(stroke
				(width 0.15)
				(type solid)
			)
			(fill none)
			(layer "B.Fab")
		)
		(fp_text user "Author: Antmicro"
			(at -0.8 -4.4 180)
			(layer "B.Fab")
			(hide yes)
			(effects
				(font
					(size 0.7 0.7)
					(thickness 0.15)
				)
				(justify left bottom mirror)
			)
		)
		(fp_text user "License: Apache-2.0"
			(at -0.8 -5.6 180)
			(layer "B.Fab")
			(hide yes)
			(effects
				(font
					(size 0.7 0.7)
					(thickness 0.15)
				)
				(justify left bottom mirror)
			)
		)
		(fp_text user "${REFERENCE}"
			(at -0.8 -3.2 180)
			(layer "B.Fab")
			(hide yes)
			(effects
				(font
					(size 0.7 0.7)
					(thickness 0.15)
				)
				(justify left bottom mirror)
			)
		)
		(pad "1" smd roundrect
			(at -0.351 0)
			(size 0.3 0.5)
			(layers "B.Cu" "B.Paste" "B.Mask")
			(roundrect_rratio 0.25)
			(net 1 "GND")
			(pinfunction "C")
			(pintype "passive")
		)
		(pad "2" smd roundrect
			(at 0.349 0)
			(size 0.3 0.5)
			(layers "B.Cu" "B.Paste" "B.Mask")
			(roundrect_rratio 0.25)
			(net 80 "/SoM/~{FORCE_RECOVERY}")
			(pinfunction "A")
			(pintype "passive")
		)
	)
	(footprint "antmicro-footprints:C_0402_1005Metric"
		(layer "B.Cu")
		(at 97.45 89.25)
		(descr "Capacitor SMD 0402")
		(tags "capacitor SMD 0402")
		(property "Reference" "C131"
			(at 3.8 0.07 180)
			(layer "B.SilkS")
			(effects
				(font
					(size 0.7 0.7)
					(thickness 0.15)
				)
				(justify left bottom mirror)
			)
		)
		(property "Value" "C_100n_0402"
			(at 0 -1.4 180)
			(layer "B.Fab")
			(effects
				(font
					(size 0.7 0.7)
					(thickness 0.15)
				)
				(justify left bottom mirror)
			)
		)
		(property "Footprint" "antmicro-footprints:C_0402_1005Metric"
			(at 0 0 0)
			(layer "F.Fab")
			(hide yes)
			(effects
				(font
					(size 1.27 1.27)
					(thickness 0.15)
				)
			)
		)
		(property "Datasheet" "https://www.murata.com/products/productdetail?partno=GRM155R61H104KE14%23"
			(at 0 0 0)
			(layer "F.Fab")
			(hide yes)
			(effects
				(font
					(size 1.27 1.27)
					(thickness 0.15)
				)
			)
		)
		(property "Author" "Antmicro"
			(at 0 0 0)
			(layer "B.Fab")
			(hide yes)
			(effects
				(font
					(size 1 1)
					(thickness 0.15)
				)
				(justify mirror)
			)
		)
		(property "Dielectric" "X5R"
			(at 0 0 0)
			(layer "B.Fab")
			(hide yes)
			(effects
				(font
					(size 1 1)
					(thickness 0.15)
				)
				(justify mirror)
			)
		)
		(property "License" "Apache-2.0"
			(at 0 0 0)
			(layer "B.Fab")
			(hide yes)
			(effects
				(font
					(size 1 1)
					(thickness 0.15)
				)
				(justify mirror)
			)
		)
		(property "MPN" "GRM155R61H104KE14D"
			(at 0 0 0)
			(layer "B.Fab")
			(hide yes)
			(effects
				(font
					(size 1 1)
					(thickness 0.15)
				)
				(justify mirror)
			)
		)
		(property "Manufacturer" "Murata"
			(at 0 0 0)
			(layer "B.Fab")
			(hide yes)
			(effects
				(font
					(size 1 1)
					(thickness 0.15)
				)
				(justify mirror)
			)
		)
		(property "Val" "100n"
			(at 0 0 0)
			(layer "B.Fab")
			(hide yes)
			(effects
				(font
					(size 1 1)
					(thickness 0.15)
				)
				(justify mirror)
			)
		)
		(property "Voltage" "50V"
			(at 0 0 0)
			(layer "B.Fab")
			(hide yes)
			(effects
				(font
					(size 1 1)
					(thickness 0.15)
				)
				(justify mirror)
			)
		)
		(sheetname "HDMI")
		(sheetfile "hdmi.kicad_sch")
		(attr smd)
		(fp_rect
			(start -0.925 0.47)
			(end 0.925 -0.47)
			(stroke
				(width 0.05)
				(type default)
			)
			(fill none)
			(layer "B.CrtYd")
		)
		(fp_line
			(start -0.494 -0.248)
			(end 0.504 -0.248)
			(stroke
				(width 0.15)
				(type solid)
			)
			(layer "B.Fab")
		)
		(fp_line
			(start -0.494 0.25)
			(end -0.494 -0.248)
			(stroke
				(width 0.15)
				(type solid)
			)
			(layer "B.Fab")
		)
		(fp_line
			(start 0.504 -0.248)
			(end 0.504 0.25)
			(stroke
				(width 0.15)
				(type solid)
			)
			(layer "B.Fab")
		)
		(fp_line
			(start 0.504 0.25)
			(end -0.494 0.25)
			(stroke
				(width 0.15)
				(type solid)
			)
			(layer "B.Fab")
		)
		(fp_text user "${REFERENCE}"
			(at -0.932 -3.168 180)
			(layer "B.Fab")
			(hide yes)
			(effects
				(font
					(size 0.7 0.7)
					(thickness 0.15)
				)
				(justify left bottom mirror)
			)
		)
		(fp_text user "Author: Antmicro"
			(at -0.932 -4.17 180)
			(layer "B.Fab")
			(hide yes)
			(effects
				(font
					(size 0.7 0.7)
					(thickness 0.15)
				)
				(justify left bottom mirror)
			)
		)
		(fp_text user "License: Apache-2.0"
			(at -0.932 -5.17 180)
			(layer "B.Fab")
			(hide yes)
			(effects
				(font
					(size 0.7 0.7)
					(thickness 0.15)
				)
				(justify left bottom mirror)
			)
		)
		(pad "1" smd roundrect
			(at -0.48 0)
			(size 0.59 0.64)
			(layers "B.Cu" "B.Paste" "B.Mask")
			(roundrect_rratio 0.25)
			(net 665 "/HDMI/DP_MUX_D0+")
			(pintype "passive")
		)
		(pad "2" smd roundrect
			(at 0.48 0)
			(size 0.59 0.64)
			(layers "B.Cu" "B.Paste" "B.Mask")
			(roundrect_rratio 0.25)
			(net 422 "DP1_TXD3_HDMI_TXC_P")
			(pintype "passive")
		)
	)
	(footprint "antmicro-footprints:C_1206_3216Metric"
		(layer "B.Cu")
		(at 31.5 72 -90)
		(descr "Capacitor SMD 1206")
		(tags "capacitor SMD 1206")
		(property "Reference" "C85"
			(at 0.8 -2 90)
			(layer "B.SilkS")
			(effects
				(font
					(size 0.7 0.7)
					(thickness 0.15)
				)
				(justify left bottom mirror)
			)
		)
		(property "Value" "C_47u_16V_1206"
			(at 0 -2.1 90)
			(layer "B.Fab")
			(effects
				(font
					(size 0.7 0.7)
					(thickness 0.15)
				)
				(justify left bottom mirror)
			)
		)
		(property "Footprint" "antmicro-footprints:C_1206_3216Metric"
			(at 0 0 -90)
			(layer "F.Fab")
			(hide yes)
			(effects
				(font
					(size 1.27 1.27)
					(thickness 0.15)
				)
			)
		)
		(property "Datasheet" "https://product.tdk.com/en/search/capacitor/ceramic/mlcc/info?part_no=C3216X5R1C476M160AB"
			(at 0 0 -90)
			(layer "F.Fab")
			(hide yes)
			(effects
				(font
					(size 1.27 1.27)
					(thickness 0.15)
				)
			)
		)
		(property "Author" "Antmicro"
			(at -40.5 103.5 0)
			(layer "B.Fab")
			(hide yes)
			(effects
				(font
					(size 1 1)
					(thickness 0.15)
				)
				(justify mirror)
			)
		)
		(property "Dielectric" "X5R"
			(at -40.5 103.5 0)
			(layer "B.Fab")
			(hide yes)
			(effects
				(font
					(size 1 1)
					(thickness 0.15)
				)
				(justify mirror)
			)
		)
		(property "License" "Apache-2.0"
			(at -40.5 103.5 0)
			(layer "B.Fab")
			(hide yes)
			(effects
				(font
					(size 1 1)
					(thickness 0.15)
				)
				(justify mirror)
			)
		)
		(property "MPN" "C3216X5R1C476M160AB"
			(at -40.5 103.5 0)
			(layer "B.Fab")
			(hide yes)
			(effects
				(font
					(size 1 1)
					(thickness 0.15)
				)
				(justify mirror)
			)
		)
		(property "Manufacturer" "TDK"
			(at -40.5 103.5 0)
			(layer "B.Fab")
			(hide yes)
			(effects
				(font
					(size 1 1)
					(thickness 0.15)
				)
				(justify mirror)
			)
		)
		(property "Public" "False"
			(at -40.5 103.5 0)
			(layer "B.Fab")
			(hide yes)
			(effects
				(font
					(size 1 1)
					(thickness 0.15)
				)
				(justify mirror)
			)
		)
		(property "Val" "47u"
			(at -40.5 103.5 0)
			(layer "B.Fab")
			(hide yes)
			(effects
				(font
					(size 1 1)
					(thickness 0.15)
				)
				(justify mirror)
			)
		)
		(property "Voltage" "16V"
			(at -40.5 103.5 0)
			(layer "B.Fab")
			(hide yes)
			(effects
				(font
					(size 1 1)
					(thickness 0.15)
				)
				(justify mirror)
			)
		)
		(sheetname "Ethernet")
		(sheetfile "ethernet.kicad_sch")
		(attr smd)
		(fp_line
			(start -0.8 0.899)
			(end 0.8 0.899)
			(stroke
				(width 0.15)
				(type solid)
			)
			(layer "B.SilkS")
		)
		(fp_line
			(start -0.8 -0.901)
			(end 0.8 -0.901)
			(stroke
				(width 0.15)
				(type solid)
			)
			(layer "B.SilkS")
		)
		(fp_rect
			(start -2.325 1.15)
			(end 2.325 -1.15)
			(stroke
				(width 0.05)
				(type default)
			)
			(fill none)
			(layer "B.CrtYd")
		)
		(fp_rect
			(start -1.6 0.799)
			(end 1.6 -0.801)
			(stroke
				(width 0.15)
				(type solid)
			)
			(fill none)
			(layer "B.Fab")
		)
		(fp_text user "License: Apache-2.0"
			(at -2.8 -6.6 90)
			(layer "B.Fab")
			(hide yes)
			(effects
				(font
					(size 0.7 0.7)
					(thickness 0.15)
				)
				(justify left bottom mirror)
			)
		)
		(fp_text user "Author: Antmicro"
			(at -2.8 -5.6 90)
			(layer "B.Fab")
			(hide yes)
			(effects
				(font
					(size 0.7 0.7)
					(thickness 0.15)
				)
				(justify left bottom mirror)
			)
		)
		(fp_text user "${REFERENCE}"
			(at -2.8 -4.6 90)
			(layer "B.Fab")
			(hide yes)
			(effects
				(font
					(size 0.7 0.7)
					(thickness 0.15)
				)
				(justify left bottom mirror)
			)
		)
		(pad "1" smd roundrect
			(at -1.5 -0.001 270)
			(size 1.15 1.8)
			(layers "B.Cu" "B.Paste" "B.Mask")
			(roundrect_rratio 0.25)
			(net 1 "GND")
			(pintype "passive")
		)
		(pad "2" smd roundrect
			(at 1.5 -0.001 270)
			(size 1.15 1.8)
			(layers "B.Cu" "B.Paste" "B.Mask")
			(roundrect_rratio 0.25)
			(net 500 "POE_OUTPUT")
			(pintype "passive")
		)
	)
	(footprint "antmicro-footprints:Fiducial_1mm_Mask2mm"
		(layer "B.Cu")
		(at 148.45 127.45 180)
		(descr "Circular Fiducial, 1mm bare copper, 3mm soldermask opening")
		(tags "fiducial")
		(property "Reference" "FID8"
			(at 0 1.4 0)
			(layer "B.SilkS")
			(hide yes)
			(effects
				(font
					(size 0.7 0.7)
					(thickness 0.15)
				)
				(justify left bottom mirror)
			)
		)
		(property "Value" "Fiducial_1mm_Mask2mm"
			(at 0 -2.2 0)
			(layer "B.Fab")
			(effects
				(font
					(size 0.7 0.7)
					(thickness 0.15)
				)
				(justify left bottom mirror)
			)
		)
		(property "Footprint" "antmicro-footprints:Fiducial_1mm_Mask2mm"
			(at 0 0 180)
			(layer "F.Fab")
			(hide yes)
			(effects
				(font
					(size 1.27 1.27)
					(thickness 0.15)
				)
			)
		)
		(attr board_only exclude_from_pos_files exclude_from_bom)
		(fp_circle
			(center 0 0)
			(end 1.24 0)
			(stroke
				(width 0.05)
				(type solid)
			)
			(fill none)
			(layer "B.CrtYd")
		)
		(fp_circle
			(center 0 0)
			(end 0.999 0)
			(stroke
				(width 0.15)
				(type solid)
			)
			(fill none)
			(layer "B.Fab")
		)
		(fp_text user "License: Apache-2.0"
			(at -1.25 -7.003 0)
			(layer "B.Fab")
			(hide yes)
			(effects
				(font
					(size 0.7 0.7)
					(thickness 0.15)
				)
				(justify left bottom mirror)
			)
		)
		(fp_text user "Author: Antmicro"
			(at -1.25 -5.803 0)
			(layer "B.Fab")
			(hide yes)
			(effects
				(font
					(size 0.7 0.7)
					(thickness 0.15)
				)
				(justify left bottom mirror)
			)
		)
		(fp_text user "${REFERENCE}"
			(at -1.25 -4.603 0)
			(layer "B.Fab")
			(hide yes)
			(effects
				(font
					(size 0.7 0.7)
					(thickness 0.15)
				)
				(justify left bottom mirror)
			)
		)
		(pad "" smd circle
			(at 0 0 180)
			(size 1 1)
			(layers "B.Cu" "B.Mask")
			(solder_mask_margin 0.5)
			(clearance 0.5)
		)
	)
)
